# S9S_MB_2U (Grand Teton) — schematic netlist excerpt (pin names and nets, part order shuffled) for the footprints in the layout excerpt that follows; sources: Cadence DE-HDL packaged netlist, KiCad conversion of 03242023_DA0F0TMBIJ0_F0T_Motherboard_J_brd_V01_OCP.brd

R759  Q_RES  150 1% CHIP  pkg 0402LF  page 132 : A = PVNN_TERM_CPU0 ; B = H_CPU_PRDY_QS_GTL_N
R40  Q_RES  127K 1% CHIP  pkg 0402LF  page 96 : A = PD_CHH_CPU0_DIMM1_SAA ; B = GND

(kicad_pcb
	(version 20260206)
	(generator "pcbnew")
	(generator_version "10.0")
	(general
		(thickness 1.6)
		(legacy_teardrops no)
	)
	(paper "A4")
	(title_block
		(title "03242023_DA0F0TMBIJ0_F0T_Motherboard_J_brd_V01_OCP.brd")
		(comment 1 "Grand Teton / footprints 5195-5196 of 6105")
	)
	(layers
		(0 "F.Cu" signal "TOP")
		(4 "In1.Cu" signal "GND")
		(6 "In2.Cu" signal "IN1")
		(8 "In3.Cu" signal "GND1")
		(10 "In4.Cu" signal "IN2")
		(12 "In5.Cu" signal "GND2")
		(14 "In6.Cu" signal "IN3")
		(16 "In7.Cu" signal "GND3")
		(18 "In8.Cu" signal "VCC")
		(20 "In9.Cu" signal "VCC1")
		(22 "In10.Cu" signal "GND4")
		(24 "In11.Cu" signal "IN4")
		(26 "In12.Cu" signal "GND5")
		(28 "In13.Cu" signal "IN5")
		(30 "In14.Cu" signal "GND6")
		(32 "In15.Cu" signal "IN6")
		(34 "In16.Cu" signal "GND7")
		(2 "B.Cu" signal "BOTTOM")
		(9 "F.Adhes" user "F.Adhesive")
		(11 "B.Adhes" user "B.Adhesive")
		(13 "F.Paste" user "Package Geometry/Pastemask Top")
		(15 "B.Paste" user "Package Geometry/Pastemask Bottom")
		(5 "F.SilkS" user "Ref Des/Silkscreen Top")
		(7 "B.SilkS" user "Ref Des/Silkscreen Bottom")
		(1 "F.Mask" user "Board Geometry/Soldermask Top")
		(3 "B.Mask" user "Board Geometry/Soldermask Bottom")
		(17 "Dwgs.User" user "User.Drawings")
		(19 "Cmts.User" user "User.Comments")
		(21 "Eco1.User" user "User.Eco1")
		(23 "Eco2.User" user "User.Eco2")
		(25 "Edge.Cuts" user "Board Geometry/Outline")
		(27 "Margin" user)
		(31 "F.CrtYd" user "Package Geometry/Place Bound Top")
		(29 "B.CrtYd" user "Package Geometry/Place Bound Bottom")
		(35 "F.Fab" user "Ref Des/Assembly Top")
		(33 "B.Fab" user "Ref Des/Assembly Bottom")
	)
	(footprint ""
		(layer "B.Cu")
		(at 84.494624 -184.096152 90)
		(property "Reference" "R759"
			(at 0 0 90)
			(layer "B.SilkS")
			(hide yes)
			(effects
				(font
					(size 1.27 1.27)
				)
				(justify mirror)
			)
		)
		(property "Value" ""
			(at 0 0 90)
			(layer "B.Fab")
			(effects
				(font
					(size 1.27 1.27)
				)
				(justify mirror)
			)
		)
		(duplicate_pad_numbers_are_jumpers no)
		(fp_line
			(start 0.7874 -0.4064)
			(end -0.7874 -0.4064)
			(stroke
				(width 0.1524)
				(type default)
			)
			(layer "B.SilkS")
		)
		(fp_line
			(start -0.7874 -0.4064)
			(end -0.7874 0.4064)
			(stroke
				(width 0.1524)
				(type default)
			)
			(layer "B.SilkS")
		)
		(fp_line
			(start 0.7874 0.4064)
			(end 0.7874 -0.4064)
			(stroke
				(width 0.1524)
				(type default)
			)
			(layer "B.SilkS")
		)
		(fp_line
			(start -0.7874 0.4064)
			(end 0.7874 0.4064)
			(stroke
				(width 0.1524)
				(type default)
			)
			(layer "B.SilkS")
		)
		(fp_line
			(start 0.67945 -0.305054)
			(end 0.12065 -0.305054)
			(stroke
				(width 0.1)
				(type default)
			)
			(layer "B.Fab")
		)
		(fp_line
			(start 0.12065 -0.305054)
			(end 0.12065 -0.2794)
			(stroke
				(width 0.1)
				(type default)
			)
			(layer "B.Fab")
		)
		(fp_line
			(start -0.12065 -0.3048)
			(end -0.67945 -0.3048)
			(stroke
				(width 0.1)
				(type default)
			)
			(layer "B.Fab")
		)
		(fp_line
			(start -0.67945 -0.3048)
			(end -0.67945 0.3048)
			(stroke
				(width 0.1)
				(type default)
			)
			(layer "B.Fab")
		)
		(fp_line
			(start 0.12065 -0.2794)
			(end -0.12065 -0.2794)
			(stroke
				(width 0.1)
				(type default)
			)
			(layer "B.Fab")
		)
		(fp_line
			(start -0.12065 -0.2794)
			(end -0.12065 -0.3048)
			(stroke
				(width 0.1)
				(type default)
			)
			(layer "B.Fab")
		)
		(fp_line
			(start 0.12065 0.2794)
			(end 0.12065 0.3048)
			(stroke
				(width 0.1)
				(type default)
			)
			(layer "B.Fab")
		)
		(fp_line
			(start -0.120396 0.2794)
			(end 0.12065 0.2794)
			(stroke
				(width 0.1)
				(type default)
			)
			(layer "B.Fab")
		)
		(fp_line
			(start 0.67945 0.3048)
			(end 0.67945 -0.305054)
			(stroke
				(width 0.1)
				(type default)
			)
			(layer "B.Fab")
		)
		(fp_line
			(start 0.12065 0.3048)
			(end 0.67945 0.3048)
			(stroke
				(width 0.1)
				(type default)
			)
			(layer "B.Fab")
		)
		(fp_line
			(start -0.120396 0.3048)
			(end -0.120396 0.2794)
			(stroke
				(width 0.1)
				(type default)
			)
			(layer "B.Fab")
		)
		(fp_line
			(start -0.67945 0.3048)
			(end -0.120396 0.3048)
			(stroke
				(width 0.1)
				(type default)
			)
			(layer "B.Fab")
		)
		(pad "1" smd circle
			(at 0.40005 0 270)
			(size 0 0)
			(layers "B.Cu" "B.Mask" "B.Paste")
			(net "PVNN_TERM_CPU0")
		)
		(pad "2" smd circle
			(at -0.40005 0 270)
			(size 0 0)
			(layers "B.Cu" "B.Mask" "B.Paste")
			(net "H_CPU_PRDY_QS_GTL_N")
		)
	)
	(footprint ""
		(layer "B.Cu")
		(at 461.419448 -318.79159 90)
		(property "Reference" "R40"
			(at 0 0 90)
			(layer "B.SilkS")
			(hide yes)
			(effects
				(font
					(size 1.27 1.27)
				)
				(justify mirror)
			)
		)
		(property "Value" ""
			(at 0 0 90)
			(layer "B.Fab")
			(effects
				(font
					(size 1.27 1.27)
				)
				(justify mirror)
			)
		)
		(duplicate_pad_numbers_are_jumpers no)
		(fp_line
			(start 0.7874 -0.4064)
			(end -0.7874 -0.4064)
			(stroke
				(width 0.1524)
				(type default)
			)
			(layer "B.SilkS")
		)
		(fp_line
			(start -0.7874 -0.4064)
			(end -0.7874 0.4064)
			(stroke
				(width 0.1524)
				(type default)
			)
			(layer "B.SilkS")
		)
		(fp_line
			(start 0.7874 0.4064)
			(end 0.7874 -0.4064)
			(stroke
				(width 0.1524)
				(type default)
			)
			(layer "B.SilkS")
		)
		(fp_line
			(start -0.7874 0.4064)
			(end 0.7874 0.4064)
			(stroke
				(width 0.1524)
				(type default)
			)
			(layer "B.SilkS")
		)
		(fp_line
			(start 0.67945 -0.305054)
			(end 0.12065 -0.305054)
			(stroke
				(width 0.1)
				(type default)
			)
			(layer "B.Fab")
		)
		(fp_line
			(start 0.12065 -0.305054)
			(end 0.12065 -0.2794)
			(stroke
				(width 0.1)
				(type default)
			)
			(layer "B.Fab")
		)
		(fp_line
			(start -0.12065 -0.3048)
			(end -0.67945 -0.3048)
			(stroke
				(width 0.1)
				(type default)
			)
			(layer "B.Fab")
		)
		(fp_line
			(start -0.67945 -0.3048)
			(end -0.67945 0.3048)
			(stroke
				(width 0.1)
				(type default)
			)
			(layer "B.Fab")
		)
		(fp_line
			(start 0.12065 -0.2794)
			(end -0.12065 -0.2794)
			(stroke
				(width 0.1)
				(type default)
			)
			(layer "B.Fab")
		)
		(fp_line
			(start -0.12065 -0.2794)
			(end -0.12065 -0.3048)
			(stroke
				(width 0.1)
				(type default)
			)
			(layer "B.Fab")
		)
		(fp_line
			(start 0.12065 0.2794)
			(end 0.12065 0.3048)
			(stroke
				(width 0.1)
				(type default)
			)
			(layer "B.Fab")
		)
		(fp_line
			(start -0.120396 0.2794)
			(end 0.12065 0.2794)
			(stroke
				(width 0.1)
				(type default)
			)
			(layer "B.Fab")
		)
		(fp_line
			(start 0.67945 0.3048)
			(end 0.67945 -0.305054)
			(stroke
				(width 0.1)
				(type default)
			)
			(layer "B.Fab")
		)
		(fp_line
			(start 0.12065 0.3048)
			(end 0.67945 0.3048)
			(stroke
				(width 0.1)
				(type default)
			)
			(layer "B.Fab")
		)
		(fp_line
			(start -0.120396 0.3048)
			(end -0.120396 0.2794)
			(stroke
				(width 0.1)
				(type default)
			)
			(layer "B.Fab")
		)
		(fp_line
			(start -0.67945 0.3048)
			(end -0.120396 0.3048)
			(stroke
				(width 0.1)
				(type default)
			)
			(layer "B.Fab")
		)
		(pad "1" smd circle
			(at 0.40005 0 270)
			(size 0 0)
			(layers "B.Cu" "B.Mask" "B.Paste")
			(net "PD_CHH_CPU0_DIMM1_SAA")
		)
		(pad "2" smd circle
			(at -0.40005 0 270)
			(size 0 0)
			(layers "B.Cu" "B.Mask" "B.Paste")
			(net "GND")
		)
	)
)
